# T6G (Grand Teton) — schematic netlist excerpt (pin names and nets, part order shuffled) for the footprints in the layout excerpt that follows; sources: Cadence DE-HDL packaged netlist, KiCad conversion of 04192023_DAF0TMB3IC0_F0TG_MB_C_brd_V02_OCP.brd

R297  Q_RES  1K 1% CHIP  pkg 0402LF  page 92 : A = PWRGD_CHG_CPU0_DIMM0 ; B = PWRGD_CHGL_CPU0
R105  Q_RES  1K 1% EMPTY  pkg 0402LF  page 100 : A = P3V3 ; B = PWRGD_CHC_CPU1_DIMM

(kicad_pcb
	(version 20260206)
	(generator "pcbnew")
	(generator_version "10.0")
	(general
		(thickness 1.6)
		(legacy_teardrops no)
	)
	(paper "A4")
	(title_block
		(title "04192023_DAF0TMB3IC0_F0TG_MB_C_brd_V02_OCP.brd")
		(comment 1 "Grand Teton / footprints 7222-7223 of 8354")
	)
	(layers
		(0 "F.Cu" signal "TOP")
		(4 "In1.Cu" signal "GND")
		(6 "In2.Cu" signal "IN1")
		(8 "In3.Cu" signal "GND1")
		(10 "In4.Cu" signal "IN2")
		(12 "In5.Cu" signal "GND2")
		(14 "In6.Cu" signal "IN3")
		(16 "In7.Cu" signal "GND3")
		(18 "In8.Cu" signal "VCC")
		(20 "In9.Cu" signal "VCC1")
		(22 "In10.Cu" signal "GND4")
		(24 "In11.Cu" signal "IN4")
		(26 "In12.Cu" signal "GND5")
		(28 "In13.Cu" signal "IN5")
		(30 "In14.Cu" signal "GND6")
		(32 "In15.Cu" signal "IN6")
		(34 "In16.Cu" signal "GND7")
		(2 "B.Cu" signal "BOTTOM")
		(9 "F.Adhes" user "F.Adhesive")
		(11 "B.Adhes" user "B.Adhesive")
		(13 "F.Paste" user "Package Geometry/Pastemask Top")
		(15 "B.Paste" user "Package Geometry/Pastemask Bottom")
		(5 "F.SilkS" user "Ref Des/Silkscreen Top")
		(7 "B.SilkS" user "Ref Des/Silkscreen Bottom")
		(1 "F.Mask" user "Board Geometry/Soldermask Top")
		(3 "B.Mask" user "Board Geometry/Soldermask Bottom")
		(17 "Dwgs.User" user "User.Drawings")
		(19 "Cmts.User" user "User.Comments")
		(21 "Eco1.User" user "User.Eco1")
		(23 "Eco2.User" user "User.Eco2")
		(25 "Edge.Cuts" user "Board Geometry/Outline")
		(27 "Margin" user)
		(31 "F.CrtYd" user "Package Geometry/Place Bound Top")
		(29 "B.CrtYd" user "Package Geometry/Place Bound Bottom")
		(35 "F.Fab" user "Ref Des/Assembly Top")
		(33 "B.Fab" user "Ref Des/Assembly Bottom")
	)
	(footprint ""
		(layer "B.Cu")
		(at 40.9956 -193.996564)
		(property "Reference" "R105"
			(at 0 0 0)
			(layer "B.SilkS")
			(hide yes)
			(effects
				(font
					(size 1.27 1.27)
				)
				(justify mirror)
			)
		)
		(property "Value" ""
			(at 0 0 0)
			(layer "B.Fab")
			(effects
				(font
					(size 1.27 1.27)
				)
				(justify mirror)
			)
		)
		(duplicate_pad_numbers_are_jumpers no)
		(fp_line
			(start -0.7874 -0.4064)
			(end -0.7874 0.4064)
			(stroke
				(width 0.1524)
				(type default)
			)
			(layer "B.SilkS")
		)
		(fp_line
			(start -0.7874 0.4064)
			(end 0.7874 0.4064)
			(stroke
				(width 0.1524)
				(type default)
			)
			(layer "B.SilkS")
		)
		(fp_line
			(start 0.7874 -0.4064)
			(end -0.7874 -0.4064)
			(stroke
				(width 0.1524)
				(type default)
			)
			(layer "B.SilkS")
		)
		(fp_line
			(start 0.7874 0.4064)
			(end 0.7874 -0.4064)
			(stroke
				(width 0.1524)
				(type default)
			)
			(layer "B.SilkS")
		)
		(fp_line
			(start -0.67945 -0.3048)
			(end -0.67945 0.3048)
			(stroke
				(width 0.1)
				(type default)
			)
			(layer "B.Fab")
		)
		(fp_line
			(start -0.67945 0.3048)
			(end -0.120396 0.3048)
			(stroke
				(width 0.1)
				(type default)
			)
			(layer "B.Fab")
		)
		(fp_line
			(start -0.12065 -0.3048)
			(end -0.67945 -0.3048)
			(stroke
				(width 0.1)
				(type default)
			)
			(layer "B.Fab")
		)
		(fp_line
			(start -0.12065 -0.2794)
			(end -0.12065 -0.3048)
			(stroke
				(width 0.1)
				(type default)
			)
			(layer "B.Fab")
		)
		(fp_line
			(start -0.120396 0.2794)
			(end 0.12065 0.2794)
			(stroke
				(width 0.1)
				(type default)
			)
			(layer "B.Fab")
		)
		(fp_line
			(start -0.120396 0.3048)
			(end -0.120396 0.2794)
			(stroke
				(width 0.1)
				(type default)
			)
			(layer "B.Fab")
		)
		(fp_line
			(start 0.12065 -0.305054)
			(end 0.12065 -0.2794)
			(stroke
				(width 0.1)
				(type default)
			)
			(layer "B.Fab")
		)
		(fp_line
			(start 0.12065 -0.2794)
			(end -0.12065 -0.2794)
			(stroke
				(width 0.1)
				(type default)
			)
			(layer "B.Fab")
		)
		(fp_line
			(start 0.12065 0.2794)
			(end 0.12065 0.3048)
			(stroke
				(width 0.1)
				(type default)
			)
			(layer "B.Fab")
		)
		(fp_line
			(start 0.12065 0.3048)
			(end 0.67945 0.3048)
			(stroke
				(width 0.1)
				(type default)
			)
			(layer "B.Fab")
		)
		(fp_line
			(start 0.67945 -0.305054)
			(end 0.12065 -0.305054)
			(stroke
				(width 0.1)
				(type default)
			)
			(layer "B.Fab")
		)
		(fp_line
			(start 0.67945 0.3048)
			(end 0.67945 -0.305054)
			(stroke
				(width 0.1)
				(type default)
			)
			(layer "B.Fab")
		)
		(pad "1" smd circle
			(at 0.40005 0 180)
			(size 0 0)
			(layers "B.Cu" "B.Mask" "B.Paste")
			(net "P3V3")
		)
		(pad "2" smd circle
			(at -0.40005 0 180)
			(size 0 0)
			(layers "B.Cu" "B.Mask" "B.Paste")
			(net "PWRGD_CHC_CPU1_DIMM")
		)
	)
	(footprint ""
		(layer "B.Cu")
		(at 412.191454 -191.20231 180)
		(property "Reference" "R297"
			(at 0 0 0)
			(layer "B.SilkS")
			(hide yes)
			(effects
				(font
					(size 1.27 1.27)
				)
				(justify mirror)
			)
		)
		(property "Value" ""
			(at 0 0 0)
			(layer "B.Fab")
			(effects
				(font
					(size 1.27 1.27)
				)
				(justify mirror)
			)
		)
		(duplicate_pad_numbers_are_jumpers no)
		(fp_line
			(start 0.7874 0.4064)
			(end 0.7874 -0.4064)
			(stroke
				(width 0.1524)
				(type default)
			)
			(layer "B.SilkS")
		)
		(fp_line
			(start 0.7874 -0.4064)
			(end -0.7874 -0.4064)
			(stroke
				(width 0.1524)
				(type default)
			)
			(layer "B.SilkS")
		)
		(fp_line
			(start -0.7874 0.4064)
			(end 0.7874 0.4064)
			(stroke
				(width 0.1524)
				(type default)
			)
			(layer "B.SilkS")
		)
		(fp_line
			(start -0.7874 -0.4064)
			(end -0.7874 0.4064)
			(stroke
				(width 0.1524)
				(type default)
			)
			(layer "B.SilkS")
		)
		(fp_line
			(start 0.67945 0.3048)
			(end 0.67945 -0.305054)
			(stroke
				(width 0.1)
				(type default)
			)
			(layer "B.Fab")
		)
		(fp_line
			(start 0.67945 -0.305054)
			(end 0.12065 -0.305054)
			(stroke
				(width 0.1)
				(type default)
			)
			(layer "B.Fab")
		)
		(fp_line
			(start 0.12065 0.3048)
			(end 0.67945 0.3048)
			(stroke
				(width 0.1)
				(type default)
			)
			(layer "B.Fab")
		)
		(fp_line
			(start 0.12065 0.2794)
			(end 0.12065 0.3048)
			(stroke
				(width 0.1)
				(type default)
			)
			(layer "B.Fab")
		)
		(fp_line
			(start 0.12065 -0.2794)
			(end -0.12065 -0.2794)
			(stroke
				(width 0.1)
				(type default)
			)
			(layer "B.Fab")
		)
		(fp_line
			(start 0.12065 -0.305054)
			(end 0.12065 -0.2794)
			(stroke
				(width 0.1)
				(type default)
			)
			(layer "B.Fab")
		)
		(fp_line
			(start -0.120396 0.3048)
			(end -0.120396 0.2794)
			(stroke
				(width 0.1)
				(type default)
			)
			(layer "B.Fab")
		)
		(fp_line
			(start -0.120396 0.2794)
			(end 0.12065 0.2794)
			(stroke
				(width 0.1)
				(type default)
			)
			(layer "B.Fab")
		)
		(fp_line
			(start -0.12065 -0.2794)
			(end -0.12065 -0.3048)
			(stroke
				(width 0.1)
				(type default)
			)
			(layer "B.Fab")
		)
		(fp_line
			(start -0.12065 -0.3048)
			(end -0.67945 -0.3048)
			(stroke
				(width 0.1)
				(type default)
			)
			(layer "B.Fab")
		)
		(fp_line
			(start -0.67945 0.3048)
			(end -0.120396 0.3048)
			(stroke
				(width 0.1)
				(type default)
			)
			(layer "B.Fab")
		)
		(fp_line
			(start -0.67945 -0.3048)
			(end -0.67945 0.3048)
			(stroke
				(width 0.1)
				(type default)
			)
			(layer "B.Fab")
		)
		(pad "1" smd circle
			(at 0.40005 0)
			(size 0 0)
			(layers "B.Cu" "B.Mask" "B.Paste")
			(net "PWRGD_CHG_CPU0_DIMM0")
		)
		(pad "2" smd circle
			(at -0.40005 0)
			(size 0 0)
			(layers "B.Cu" "B.Mask" "B.Paste")
			(net "PWRGD_CHGL_CPU0")
		)
	)
)
